# T6G (Grand Teton) — schematic parts with pin connectivity, parts 2603–2603 of 8303; source: Cadence DE-HDL packaged netlist (pstxprt.dat, pstxnet.dat, pstchip.dat)

J21  SCONN288_DDR506112002KQ  IO  pkg DDR288S_1-1VXC  page 90
  1  VIN_BULK0  POWER  = P12V_MEM_CPU0
  2  RFU0  TRI  = NC
  3  VIN_MGMT  POWER  = P3V3_AUX
  4  HSCL  IN  = I3C_SPD_DDRE_CPU0_SCL
  5  HSDA  BI  = I3C_SPD_DDRE_CPU0_SDA
  6  VSS0  POWER  = GND
  7  DQ0_A  BI  = M_E_CPU0_SA_DQ<0>
  8  VSS1  POWER  = GND
  9  DQ1_A  BI  = M_E_CPU0_SA_DQ<1>
  10  VSS2  POWER  = GND
  11  DQS0_A_T  BI  = M_E_CPU0_SA_DQS_DP<0>
  12  DQS0_A_C  BI  = M_E_CPU0_SA_DQS_DN<0>
  13  VSS3  POWER  = GND
  14  DQ4_A  BI  = M_E_CPU0_SA_DQ<4>
  15  VSS4  POWER  = GND
  16  DQ5_A  BI  = M_E_CPU0_SA_DQ<5>
  17  VSS5  POWER  = GND
  18  DQ8_A  BI  = M_E_CPU0_SA_DQ<8>
  19  VSS6  POWER  = GND
  20  DQ9_A  BI  = M_E_CPU0_SA_DQ<9>
  21  VSS7  POWER  = GND
  22  DQS1_A_T  BI  = M_E_CPU0_SA_DQS_DP<1>
  23  DQS1_A_C  BI  = M_E_CPU0_SA_DQS_DN<1>
  24  VSS8  POWER  = GND
  25  DQ12_A  BI  = M_E_CPU0_SA_DQ<12>
  26  VSS9  POWER  = GND
  27  DQ13_A  BI  = M_E_CPU0_SA_DQ<13>
  28  VSS10  POWER  = GND
  29  DQ16_A  BI  = M_E_CPU0_SA_DQ<16>
  30  VSS11  POWER  = GND
  31  DQ17_A  BI  = M_E_CPU0_SA_DQ<17>
  32  VSS12  POWER  = GND
  33  DQS2_A_T  BI  = M_E_CPU0_SA_DQS_DP<2>
  34  DQS2_A_C  BI  = M_E_CPU0_SA_DQS_DN<2>
  35  VSS13  POWER  = GND
  36  DQ20_A  BI  = M_E_CPU0_SA_DQ<20>
  37  VSS14  POWER  = GND
  38  DQ21_A  BI  = M_E_CPU0_SA_DQ<21>
  39  VSS15  POWER  = GND
  40  DQ24_A  BI  = M_E_CPU0_SA_DQ<24>
  41  VSS16  POWER  = GND
  42  DQ25_A  BI  = M_E_CPU0_SA_DQ<25>
  43  VSS17  POWER  = GND
  44  DQS3_A_T  BI  = M_E_CPU0_SA_DQS_DP<3>
  45  DQS3_A_C  BI  = M_E_CPU0_SA_DQS_DN<3>
  46  VSS18  POWER  = GND
  47  DQ28_A  BI  = M_E_CPU0_SA_DQ<28>
  48  VSS19  POWER  = GND
  49  DQ29_A  BI  = M_E_CPU0_SA_DQ<29>
  50  VSS20  POWER  = GND
  51  CB0_A  BI  = M_E_CPU0_SA_CB<0>
  52  VSS21  POWER  = GND
  53  CB1_A  BI  = M_E_CPU0_SA_CB<1>
  54  VSS22  POWER  = GND
  55  DQS4_A_T  BI  = M_E_CPU0_SA_DQS_DP<4>
  56  DQS4_A_C  BI  = M_E_CPU0_SA_DQS_DN<4>
  57  VSS23  POWER  = GND
  58  CB4_A  BI  = M_E_CPU0_SA_CB<4>
  59  VSS24  POWER  = GND
  60  CB5_A  BI  = M_E_CPU0_SA_CB<5>
  61  VSS25  POWER  = GND
  62  ALERT_N  OUT  = M_E_CPU0_ALERT_N
  63  VSS26  POWER  = GND
  64  CS0_A_N  IN  = M_E_CPU0_SA_CS_N<0>
  65  VSS27  POWER  = GND
  66  CA0_A  IN  = M_E_CPU0_SA_CA<0>
  67  VSS28  POWER  = GND
  68  CA2_A  IN  = M_E_CPU0_SA_CA<2>
  69  VSS29  POWER  = GND
  70  CA4_A  IN  = M_E_CPU0_SA_CA<4>
  71  VSS30  POWER  = GND
  72  CA6_A  IN  = M_E_CPU0_SA_CA<6>
  73  VSS31  POWER  = GND
  74  PAR_A  IN  = M_E_CPU0_SA_PAR
  75  VSS32  POWER  = GND
  76  CA0_B  IN  = M_E_CPU0_SB_CA<0>
  77  VSS33  POWER  = GND
  78  CA2_B  IN  = M_E_CPU0_SB_CA<2>
  79  VSS34  POWER  = GND
  80  CA4_B  IN  = M_E_CPU0_SB_CA<4>
  81  VSS35  POWER  = GND
  82  CA6_B  IN  = M_E_CPU0_SB_CA<6>
  83  VSS36  POWER  = GND
  84  CS0_B_N  IN  = M_E_CPU0_SB_CS_N<0>
  85  VSS37  POWER  = GND
  86  \lbd||rsp_a_n\  OUT  = M_E_CPU0_SA_RSP<0>
  87  \lbs||rsp_b_n\  OUT  = M_E_CPU0_SB_RSP<0>
  88  VSS38  POWER  = GND
  89  CB4_B  BI  = M_E_CPU0_SB_CB<4>
  90  VSS39  POWER  = GND
  91  CB5_B  BI  = M_E_CPU0_SB_CB<5>
  92  VSS40  POWER  = GND
  93  \dqs9_b_t||tdqs9_b_t||dbi4_b_n\  BI  = M_E_CPU0_SB_DQS_DP<9>
  94  \dqs9_b_c||tdqs9_b_c\  BI  = M_E_CPU0_SB_DQS_DN<9>
  95  VSS41  POWER  = GND
  96  CB0_B  BI  = M_E_CPU0_SB_CB<0>
  97  VSS42  POWER  = GND
  98  CB1_B  BI  = M_E_CPU0_SB_CB<1>
  99  VSS43  POWER  = GND
  100  DQ0_B  BI  = M_E_CPU0_SB_DQ<0>
  101  VSS44  POWER  = GND
  102  DQ1_B  BI  = M_E_CPU0_SB_DQ<1>
  103  VSS45  POWER  = GND
  104  DQS0_B_T  BI  = M_E_CPU0_SB_DQS_DP<0>
  105  DQS0_B_C  BI  = M_E_CPU0_SB_DQS_DN<0>
  106  VSS46  POWER  = GND
  107  DQ4_B  BI  = M_E_CPU0_SB_DQ<4>
  108  VSS47  POWER  = GND
  109  DQ5_B  BI  = M_E_CPU0_SB_DQ<5>
  110  VSS48  POWER  = GND
  111  DQ8_B  BI  = M_E_CPU0_SB_DQ<8>
  112  VSS49  POWER  = GND
  113  DQ9_B  BI  = M_E_CPU0_SB_DQ<9>
  114  VSS50  POWER  = GND
  115  DQS1_B_T  BI  = M_E_CPU0_SB_DQS_DP<1>
  116  DQS1_B_C  BI  = M_E_CPU0_SB_DQS_DN<1>
  117  VSS51  POWER  = GND
  118  DQ12_B  BI  = M_E_CPU0_SB_DQ<12>
  119  VSS52  POWER  = GND
  120  DQ13_B  BI  = M_E_CPU0_SB_DQ<13>
  121  VSS53  POWER  = GND
  122  DQ16_B  BI  = M_E_CPU0_SB_DQ<16>
  123  VSS54  POWER  = GND
  124  DQ17_B  BI  = M_E_CPU0_SB_DQ<17>
  125  VSS55  POWER  = GND
  126  DQS2_B_T  BI  = M_E_CPU0_SB_DQS_DP<2>
  127  DQS2_B_C  BI  = M_E_CPU0_SB_DQS_DN<2>
  128  VSS56  POWER  = GND
  129  DQ20_B  BI  = M_E_CPU0_SB_DQ<20>
  130  VSS57  POWER  = GND
  131  DQ21_B  BI  = M_E_CPU0_SB_DQ<21>
  132  VSS58  POWER  = GND
  133  DQ24_B  BI  = M_E_CPU0_SB_DQ<24>
  134  VSS59  POWER  = GND
  135  DQ25_B  BI  = M_E_CPU0_SB_DQ<25>
  136  VSS60  POWER  = GND
  137  DQS3_B_T  BI  = M_E_CPU0_SB_DQS_DP<3>
  138  DQS3_B_C  BI  = M_E_CPU0_SB_DQS_DN<3>
  139  VSS61  POWER  = GND
  140  DQ28_B  BI  = M_E_CPU0_SB_DQ<28>
  141  VSS62  POWER  = GND
  142  DQ29_B  BI  = M_E_CPU0_SB_DQ<29>
  143  VSS63  POWER  = GND
  144  RFU1  TRI  = NC
  145  VIN_BULK1  POWER  = P12V_MEM_CPU0
  146  VIN_BULK2  POWER  = P12V_MEM_CPU0
  147  \pwr_good||fail_n\  BI  = PWRGD_CHE_CPU0_DIMM
  148  HAS  IN  = PD_CHE_CPU0_DIMM_SAA
  149  RFU2  TRI  = NC
  150  RFU3  TRI  = NC
  151  VSS64  POWER  = GND
  152  DQ2_A  BI  = M_E_CPU0_SA_DQ<2>
  153  VSS65  POWER  = GND
  154  DQ3_A  BI  = M_E_CPU0_SA_DQ<3>
  155  VSS66  POWER  = GND
  156  \dqs5_a_c||tdqs5_a_c||dqs5_a_t||tdqs5_a_t\  BI  = M_E_CPU0_SA_DQS_DN<5>
  157  \dqs5_a_t||tdqs5_a_t\  BI  = M_E_CPU0_SA_DQS_DP<5>
  158  VSS67  POWER  = GND
  159  DQ6_A  BI  = M_E_CPU0_SA_DQ<6>
  160  VSS68  POWER  = GND
  161  DQ7_A  BI  = M_E_CPU0_SA_DQ<7>
  162  VSS69  POWER  = GND
  163  DQ10_A  BI  = M_E_CPU0_SA_DQ<10>
  164  VSS70  POWER  = GND
  165  DQ11_A  BI  = M_E_CPU0_SA_DQ<11>
  166  VSS71  POWER  = GND
  167  \dqs6_a_c||tdqs6_a_c||dqs6_a_t||tdqs6_a_t\  BI  = M_E_CPU0_SA_DQS_DN<6>
  168  \dqs6_a_t||tdqs6_a_t\  BI  = M_E_CPU0_SA_DQS_DP<6>
  169  VSS72  POWER  = GND
  170  DQ14_A  BI  = M_E_CPU0_SA_DQ<14>
  171  VSS73  POWER  = GND
  172  DQ15_A  BI  = M_E_CPU0_SA_DQ<15>
  173  VSS74  POWER  = GND
  174  DQ18_A  BI  = M_E_CPU0_SA_DQ<18>
  175  VSS75  POWER  = GND
  176  DQ19_A  BI  = M_E_CPU0_SA_DQ<19>
  177  VSS76  POWER  = GND
  178  \dqs7_a_c||tdqs7_a_c\  BI  = M_E_CPU0_SA_DQS_DN<7>
  179  \dqs7_a_t||tdqs7_a_t\  BI  = M_E_CPU0_SA_DQS_DP<7>
  180  VSS77  POWER  = GND
  181  DQ22_A  BI  = M_E_CPU0_SA_DQ<22>
  182  VSS78  POWER  = GND
  183  DQ23_A  BI  = M_E_CPU0_SA_DQ<23>
  184  VSS79  POWER  = GND
  185  DQ26_A  BI  = M_E_CPU0_SA_DQ<26>
  186  VSS80  POWER  = GND
  187  DQ27_A  BI  = M_E_CPU0_SA_DQ<27>
  188  VSS81  POWER  = GND
  189  \dqs8_a_c||tdqs8_a_c\  BI  = M_E_CPU0_SA_DQS_DN<8>
  190  \dqs8_a_t||tdqs8_a_t\  BI  = M_E_CPU0_SA_DQS_DP<8>
  191  VSS82  POWER  = GND
  192  DQ30_A  BI  = M_E_CPU0_SA_DQ<30>
  193  VSS83  POWER  = GND
  194  DQ31_A  BI  = M_E_CPU0_SA_DQ<31>
  195  VSS84  POWER  = GND
  196  CB2_A  BI  = M_E_CPU0_SA_CB<2>
  197  VSS85  POWER  = GND
  198  CB3_A  BI  = M_E_CPU0_SA_CB<3>
  199  VSS86  POWER  = GND
  200  \dqs9_a_c||tdqs9_a_c\  BI  = M_E_CPU0_SA_DQS_DN<9>
  201  \dqs9_a_t||tdqs9_a_t\  BI  = M_E_CPU0_SA_DQS_DP<9>
  202  VSS87  POWER  = GND
  203  CB6_A  BI  = M_E_CPU0_SA_CB<6>
  204  VSS88  POWER  = GND
  205  CB7_A  BI  = M_E_CPU0_SA_CB<7>
  206  VSS89  POWER  = GND
  207  RESET_N  IN  = M_E_CPU0_RESET_N
  208  VSS90  POWER  = GND
  209  CS1_A_N  IN  = M_E_CPU0_SA_CS_N<1>
  210  VSS91  POWER  = GND
  211  CA1_A  IN  = M_E_CPU0_SA_CA<1>
  212  VSS92  POWER  = GND
  213  CA3_A  IN  = M_E_CPU0_SA_CA<3>
  214  VSS93  POWER  = GND
  215  CA5_A  IN  = M_E_CPU0_SA_CA<5>
  216  VSS94  POWER  = GND
  217  CK_T  IN  = M_E_CPU0_CLK_DP<0>
  218  CK_C  IN  = M_E_CPU0_CLK_DN<0>
  219  VSS95  POWER  = GND
  220  RFU4  TRI  = NC
  221  CA1_B  IN  = M_E_CPU0_SB_CA<1>
  222  VSS96  POWER  = GND
  223  CA3_B  IN  = M_E_CPU0_SB_CA<3>
  224  VSS97  POWER  = GND
  225  CA5_B  IN  = M_E_CPU0_SB_CA<5>
  226  VSS98  POWER  = GND
  227  PAR_B  IN  = M_E_CPU0_SB_PAR
  228  VSS99  POWER  = GND
  229  CS1_B_N  IN  = M_E_CPU0_SB_CS_N<1>
  230  VSS100  POWER  = GND
  231  RFU5  TRI  = NC
  232  RFU6  TRI  = NC
  233  VSS101  POWER  = GND
  234  CB6_B  BI  = M_E_CPU0_SB_CB<6>
  235  VSS102  POWER  = GND
  236  CB7_B  BI  = M_E_CPU0_SB_CB<7>
  237  VSS103  POWER  = GND
  238  DQS4_B_C  BI  = M_E_CPU0_SB_DQS_DN<4>
  239  DQS4_B_T  BI  = M_E_CPU0_SB_DQS_DP<4>
  240  VSS104  POWER  = GND
  241  CB2_B  BI  = M_E_CPU0_SB_CB<2>
  242  VSS105  POWER  = GND
  243  CB3_B  BI  = M_E_CPU0_SB_CB<3>
  244  VSS106  POWER  = GND
  245  DQ2_B  BI  = M_E_CPU0_SB_DQ<2>
  246  VSS107  POWER  = GND
  247  DQ3_B  BI  = M_E_CPU0_SB_DQ<3>
  248  VSS108  POWER  = GND
  249  \dqs5_b_c||tdqs5_b_c\  BI  = M_E_CPU0_SB_DQS_DN<5>
  250  \dqs5_b_t||tdqs5_b_t\  BI  = M_E_CPU0_SB_DQS_DP<5>
  251  VSS109  POWER  = GND
  252  DQ6_B  BI  = M_E_CPU0_SB_DQ<6>
  253  VSS110  POWER  = GND
  254  DQ7_B  BI  = M_E_CPU0_SB_DQ<7>
  255  VSS111  POWER  = GND
  256  DQ10_B  BI  = M_E_CPU0_SB_DQ<10>
  257  VSS112  POWER  = GND
  258  DQ11_B  BI  = M_E_CPU0_SB_DQ<11>
  259  VSS113  POWER  = GND
  260  \dqs6_b_c||tdqs6_b_c\  BI  = M_E_CPU0_SB_DQS_DN<6>
  261  \dqs6_b_t||tdqs6_b_t\  BI  = M_E_CPU0_SB_DQS_DP<6>
  262  VSS114  POWER  = GND
  263  DQ14_B  BI  = M_E_CPU0_SB_DQ<14>
  264  VSS115  POWER  = GND
  265  DQ15_B  BI  = M_E_CPU0_SB_DQ<15>
  266  VSS116  POWER  = GND
  267  DQ18_B  BI  = M_E_CPU0_SB_DQ<18>
  268  VSS117  POWER  = GND
  269  DQ19_B  BI  = M_E_CPU0_SB_DQ<19>
  270  VSS118  POWER  = GND
  271  \dqs7_b_c||tdqs7_b_c\  BI  = M_E_CPU0_SB_DQS_DN<7>
  272  \dqs7_b_t||tdqs7_b_t\  BI  = M_E_CPU0_SB_DQS_DP<7>
  273  VSS119  POWER  = GND
  274  DQ22_B  BI  = M_E_CPU0_SB_DQ<22>
  275  VSS120  POWER  = GND
  276  DQ23_B  BI  = M_E_CPU0_SB_DQ<23>
  277  VSS121  POWER  = GND
  278  DQ26_B  BI  = M_E_CPU0_SB_DQ<26>
  279  VSS122  POWER  = GND
  280  DQ27_B  BI  = M_E_CPU0_SB_DQ<27>
  281  VSS123  POWER  = GND
  282  \dqs8_b_c||tdqs8_b_c\  BI  = M_E_CPU0_SB_DQS_DN<8>
  283  \dqs8_b_t||tdqs8_b_t\  BI  = M_E_CPU0_SB_DQS_DP<8>
  284  VSS124  POWER  = GND
  285  DQ30_B  BI  = M_E_CPU0_SB_DQ<30>
  286  VSS125  POWER  = GND
  287  DQ31_B  BI  = M_E_CPU0_SB_DQ<31>
  288  VSS126  POWER  = GND
  G1  G1  POWER  = GND
  G2  G2  POWER  = GND
  G3  G3  POWER  = GND
